#ISCELL
  cls sheet_a1 *
  *
#ISCELL
  cls offpage_out *
  page14_i104
#CELL
  passive resistor *
  page14_i107
#CELL
  passive resistor *
  page14_i108
#CELL
  discrete optical *
  page14_i11
#CELL
  passive resistor *
  page14_i110
#ISCELL
  cls offpage_out *
  page14_i119
#CELL
  discrete optical *
  page14_i12
#ISCELL
  cls offpage_out *
  page14_i120
#ISCELL
  cls offpage_out *
  page14_i121
#ISCELL
  cls offpage_out *
  page14_i122
#ISCELL
  cls offpage_out *
  page14_i123
#ISCELL
  cls offpage_out *
  page14_i124
#ISCELL
  cls offpage_out *
  page14_i125
#ISCELL
  cls offpage_out *
  page14_i126
#ISCELL
  cls offpage_out *
  page14_i127
#ISCELL
  cls vcc *
  page14_i128
#ISCELL
  cls offpage_out *
  page14_i133
#ISCELL
  cls offpage_out *
  page14_i134
#ISCELL
  cls offpage_out *
  page14_i135
#CELL
  discrete optical *
  page14_i136
#CELL
  discrete optical *
  page14_i137
#CELL
  discrete optical *
  page14_i138
#CELL
  discrete optical *
  page14_i139
#CELL
  discrete optical *
  page14_i140
#CELL
  discrete optical *
  page14_i141
#CELL
  discrete optical *
  page14_i142
#CELL
  discrete optical *
  page14_i143
#CELL
  passive resistor *
  page14_i146
#CELL
  passive resistor *
  page14_i147
#CELL
  passive resistor *
  page14_i148
#CELL
  passive resistor *
  page14_i149
#CELL
  passive resistor *
  page14_i150
#CELL
  passive resistor *
  page14_i151
#CELL
  passive resistor *
  page14_i152
#CELL
  passive resistor *
  page14_i153
#CELL
  passive resistor *
  page14_i154
#CELL
  passive resistor *
  page14_i155
#CELL
  passive resistor *
  page14_i156
#CELL
  passive resistor *
  page14_i157
#ISCELL
  cls offpage_out *
  page14_i159
#CELL
  passive resistor *
  page14_i160
#CELL
  passive resistor *
  page14_i161
#ISCELL
  cls offpage_out *
  page14_i162
#CELL
  passive resistor *
  page14_i163
#ISCELL
  cls offpage_out *
  page14_i164
#CELL
  passive resistor *
  page14_i165
#ISCELL
  cls offpage_out *
  page14_i166
#ISCELL
  cls offpage_out *
  page14_i167
#CELL
  passive resistor *
  page14_i168
#ISCELL
  cls offpage_out *
  page14_i169
#CELL
  passive resistor *
  page14_i170
#CELL
  passive resistor *
  page14_i171
#ISCELL
  cls offpage_out *
  page14_i172
#ISCELL
  cls offpage_out *
  page14_i173
#CELL
  passive resistor *
  page14_i174
#ISCELL
  cls offpage_out *
  page14_i175
#CELL
  passive resistor *
  page14_i176
#CELL
  passive resistor *
  page14_i177
#ISCELL
  cls offpage_out *
  page14_i178
#CELL
  passive resistor *
  page14_i179
#ISCELL
  cls offpage_out *
  page14_i180
#CELL
  passive resistor *
  page14_i181
#ISCELL
  cls offpage_out *
  page14_i182
#ISCELL
  cls offpage_out *
  page14_i183
#CELL
  passive resistor *
  page14_i184
#ISCELL
  cls offpage_out *
  page14_i185
#CELL
  passive resistor *
  page14_i186
#ISCELL
  cls offpage_out *
  page14_i187
#CELL
  passive resistor *
  page14_i188
#CELL
  passive resistor *
  page14_i190
#CELL
  discrete optical *
  page14_i191
#CELL
  passive resistor *
  page14_i192
#CELL
  discrete optical *
  page14_i194
#ISCELL
  cls vcc *
  page14_i195
#ISCELL
  cls vcc *
  page14_i196
#CELL
  interface is32fl3207_qwla3_tr_qfn29 *
  page14_i219
#ISCELL
  cls offpage_out *
  page14_i232
#ISCELL
  cls offpage_out *
  page14_i233
#ISCELL
  cls offpage_out *
  page14_i234
#ISCELL
  cls gnd_sg *
  page14_i235
#ISCELL
  cls vcc *
  page14_i236
#CELL
  passive capacitor *
  page14_i237
#CELL
  passive capacitor *
  page14_i238
#ISCELL
  cls gnd_sg *
  page14_i239
#CELL
  passive resistor *
  page14_i246
#CELL
  passive resistor *
  page14_i247
#ISCELL
  cls gnd_sg *
  page14_i248
#CELL
  passive resistor *
  page14_i249
#CELL
  passive capacitor *
  page14_i250
#ISCELL
  cls gnd_sg *
  page14_i252
#ISCELL
  cls offpage_in *
  page14_i254
#CELL
  passive resistor *
  page14_i257
#CELL
  passive resistor *
  page14_i258
#CELL
  passive resistor *
  page14_i259
#CELL
  passive resistor *
  page14_i261
#ISCELL
  cls offpage_in *
  page14_i262
#ISCELL
  cls offpage_bi *
  page14_i263
#CELL
  passive resistor *
  page14_i264
#CELL
  discrete led_4p_v14 *
  page14_i265
#CELL
  discrete led_4p_v14 *
  page14_i266
#CELL
  discrete led_4p_v14 *
  page14_i267
#CELL
  discrete led_4p_v14 *
  page14_i268
#CELL
  discrete led_4p_v14 *
  page14_i269
#ISCELL
  cls offpage_out *
  page14_i270
#ISCELL
  cls offpage_out *
  page14_i277
#ISCELL
  cls offpage_out *
  page14_i278
#ISCELL
  cls offpage_out *
  page14_i279
#ISCELL
  cls offpage_out *
  page14_i280
#ISCELL
  cls offpage_out *
  page14_i281
#ISCELL
  cls offpage_out *
  page14_i282
#ISCELL
  cls offpage_out *
  page14_i283
#ISCELL
  cls offpage_out *
  page14_i284
#ISCELL
  cls offpage_out *
  page14_i285
#ISCELL
  cls offpage_out *
  page14_i286
#ISCELL
  cls offpage_out *
  page14_i287
#CELL
  passive resistor *
  page14_i288
#CELL
  discrete optical *
  page14_i289
#ISCELL
  cls vcc *
  page14_i290
#ISCELL
  cls offpage_in *
  page14_i291
#CELL
  discrete optical *
  page14_i292
#CELL
  passive resistor *
  page14_i293
#ISCELL
  cls gnd_sg *
  page14_i294
#ISCELL
  cls offpage_in *
  page14_i295
#ISCELL
  cls offpage_bi *
  page14_i296
#ISCELL
  cls offpage_in *
  page14_i297
#CELL
  passive resistor *
  page14_i298
#CELL
  passive resistor *
  page14_i299
#ISCELL
  cls offpage_out *
  page14_i3
#ISCELL
  cls vcc *
  page14_i39
#CELL
  passive resistor *
  page14_i44
#ISCELL
  cls vcc *
  page14_i50
#ISCELL
  cls gnd_sg *
  page14_i51
#ISCELL
  cls vcc *
  page14_i57
#CELL
  passive resistor *
  page14_i58
#ISCELL
  cls vcc *
  page14_i59
#CELL
  passive resistor *
  page14_i60
#ISCELL
  cls vcc *
  page14_i62
#CELL
  passive resistor *
  page14_i63
#CELL
  passive resistor *
  page14_i65
#CELL
  passive resistor *
  page14_i66
#CELL
  passive resistor *
  page14_i67
#CELL
  passive resistor *
  page14_i68
#CELL
  passive resistor *
  page14_i69
#ISCELL
  cls offpage_out *
  page14_i7
#CELL
  passive resistor *
  page14_i70
#CELL
  passive resistor *
  page14_i72
#ISCELL
  cls offpage_out *
  page14_i73
#CELL
  passive resistor *
  page14_i74
#ISCELL
  cls offpage_out *
  page14_i76
#ISCELL
  cls offpage_out *
  page14_i8
#ISCELL
  cls offpage_out *
  page14_i87
#ISCELL
  cls offpage_out *
  page14_i88
#ISCELL
  cls offpage_out *
  page14_i9
